(kicad_pcb
	(version 20241229)
	(generator "pcbnew")
	(generator_version "9.0")
	(general
		(thickness 1.599998)
		(legacy_teardrops no)
	)
	(paper "A4")
	(title_block
		(title "Artix - Datacenter Secure Control Module (DC-SCM)")
		(date "2024-11-06")
		(rev "1.1.3")
		(comment 9 "footprint 214 of 544 (J9), pads 92-168 of 168")
	)
	(layers
		(0 "F.Cu" signal)
		(4 "In1.Cu" signal)
		(6 "In2.Cu" signal)
		(8 "In3.Cu" signal)
		(10 "In4.Cu" signal)
		(12 "In5.Cu" signal)
		(14 "In6.Cu" signal)
		(2 "B.Cu" signal)
		(9 "F.Adhes" user "F.Adhesive")
		(11 "B.Adhes" user "B.Adhesive")
		(13 "F.Paste" user)
		(15 "B.Paste" user)
		(5 "F.SilkS" user "F.Silkscreen")
		(7 "B.SilkS" user "B.Silkscreen")
		(1 "F.Mask" user)
		(3 "B.Mask" user)
		(17 "Dwgs.User" user "User.Drawings")
		(19 "Cmts.User" user "User.Comments")
		(21 "Eco1.User" user "User.Eco1")
		(23 "Eco2.User" user "User.Eco2")
		(25 "Edge.Cuts" user)
		(27 "Margin" user)
		(31 "F.CrtYd" user "F.Courtyard")
		(29 "B.CrtYd" user "B.Courtyard")
		(35 "F.Fab" user)
		(33 "B.Fab" user)
	)
	(footprint "antmicro-footprints:SFF-TA-1002-4C+"
		(layer "F.Cu")
		(at 104.89 177.355)
		(property "Reference" "J9"
			(at -29.6 3.3 0)
			(layer "F.SilkS")
			(hide yes)
			(effects
				(font
					(size 0.7 0.7)
					(thickness 0.15)
				)
				(justify left bottom)
			)
		)
		(property "Value" "SFF-TA-1002-4C+"
			(at 0 4.1 0)
			(layer "F.Fab")
			(effects
				(font
					(size 0.7 0.7)
					(thickness 0.15)
				)
				(justify left bottom)
			)
		)
		(property "Datasheet" "https://cdn.amphenol-icc.com/media/wysiwyg/files/documentation/sme005.pdf?__cf_chl_jschl_tk__=4604d1306574a1ee474ea914090d3e0c57e266a6-1606907014-0-AbkYBTCTl__kMBcY3BDmgKpfUy32FqitwN2Lniuy8W-uyv2Ev04Q-Q5Mr7srIz_Wnur0_9chB4CRbxKSYcEh7IvAJYsUgJ0PWIS5YdRqqHg567uaZciEX2hQP4ss5l6M4XdNrxEjJppHvyRV3ku89t-VmUSzhgCb8oJlyHpTxST4dEmKZNXfM53TM0tmGirdVbCRt1Byrx5pkz_uMvNABIOj7B2-eDGK52J3DWRD76zEyjdxY7Iz11gPiOY5i_QGIR3uOwkR5LBPNXe8zGqAf8--AKa7RqDbIriQRt90_32C4zIuHqbGa05BXS135E65ov80PbVcb4eSiutCqcJUAacUwu3eVnXVeIumfihJxuP8Rv7_n6saeG_2IuQpEiskzovLGKZM3667Y-rm-AL1NRXTamtvBxqTk0vyMvZ60FgJ"
			(at 0 0 0)
			(layer "F.Fab")
			(hide yes)
			(effects
				(font
					(size 1.27 1.27)
					(thickness 0.15)
				)
			)
		)
		(property "Description" "PCB EDGE PCI connector"
			(at 0 0 0)
			(layer "F.Fab")
			(hide yes)
			(effects
				(font
					(size 1.27 1.27)
					(thickness 0.15)
				)
			)
		)
		(property "Author" "Antmicro"
			(at 0 0 0)
			(layer "F.Fab")
			(hide yes)
			(effects
				(font
					(size 1 1)
					(thickness 0.15)
				)
			)
		)
		(property "License" "Apache-2.0"
			(at 0 0 0)
			(layer "F.Fab")
			(hide yes)
			(effects
				(font
					(size 1 1)
					(thickness 0.15)
				)
			)
		)
		(property "MPN" ""
			(at 0 0 0)
			(layer "F.Fab")
			(hide yes)
			(effects
				(font
					(size 1 1)
					(thickness 0.15)
				)
			)
		)
		(property "Manufacturer" ""
			(at 0 0 0)
			(layer "F.Fab")
			(hide yes)
			(effects
				(font
					(size 1 1)
					(thickness 0.15)
				)
			)
		)
		(property "DNP" ""
			(at 0 0 0)
			(unlocked yes)
			(layer "F.Fab")
			(hide yes)
			(effects
				(font
					(size 1 1)
					(thickness 0.15)
				)
			)
		)
		(sheetname "/Edge connector/")
		(sheetfile "edge-connector.kicad_sch")
		(attr exclude_from_pos_files exclude_from_bom allow_missing_courtyard)
		(pad "B22" smd rect
			(at -5.6 -0.2)
			(size 0.38 1.72)
			(layers "F.Cu" "F.Mask")
			(net 80 "NCSI_TXD1")
			(pinfunction "B22")
			(pintype "passive")
		)
		(pad "B23" smd rect
			(at -5 -0.2)
			(size 0.38 1.72)
			(layers "F.Cu" "F.Mask")
			(net 81 "NCSI_RXER")
			(pinfunction "B23")
			(pintype "passive")
		)
		(pad "B24" smd rect
			(at -4.4 -0.2)
			(size 0.38 1.72)
			(layers "F.Cu" "F.Mask")
			(net 82 "NCSI_RXD0")
			(pinfunction "B24")
			(pintype "passive")
		)
		(pad "B25" smd rect
			(at -3.8 -0.2)
			(size 0.38 1.72)
			(layers "F.Cu" "F.Mask")
			(net 83 "NCSI_RXD1")
			(pinfunction "B25")
			(pintype "passive")
		)
		(pad "B26" smd rect
			(at -3.2 0)
			(size 0.38 2.12)
			(layers "F.Cu" "F.Mask")
			(net 1 "GND")
			(pinfunction "B26")
			(pintype "passive")
		)
		(pad "B27" smd rect
			(at -2.6 -0.2)
			(size 0.38 1.72)
			(layers "F.Cu" "F.Mask")
			(net 84 "PECI_BMC")
			(pinfunction "B27")
			(pintype "passive")
		)
		(pad "B28" smd rect
			(at -2 -0.2)
			(size 0.38 1.72)
			(layers "F.Cu" "F.Mask")
			(net 85 "PVCCIO_PECI")
			(pinfunction "B28")
			(pintype "passive")
		)
		(pad "B29" smd rect
			(at 2.01 -0.2)
			(size 0.38 1.72)
			(layers "F.Cu" "F.Mask")
			(net 86 "SGPIO0_DO")
			(pinfunction "B29")
			(pintype "passive")
		)
		(pad "B30" smd rect
			(at 2.6 -0.2)
			(size 0.38 1.72)
			(layers "F.Cu" "F.Mask")
			(net 87 "SGPIO0_CLK")
			(pinfunction "B30")
			(pintype "passive")
		)
		(pad "B31" smd rect
			(at 3.2 -0.2)
			(size 0.38 1.72)
			(layers "F.Cu" "F.Mask")
			(net 88 "SGPIO0_DI")
			(pinfunction "B31")
			(pintype "passive")
		)
		(pad "B32" smd rect
			(at 3.8 -0.2)
			(size 0.38 1.72)
			(layers "F.Cu" "F.Mask")
			(net 89 "SGPIO0_LD")
			(pinfunction "B32")
			(pintype "passive")
		)
		(pad "B33" smd rect
			(at 4.4 0)
			(size 0.38 2.12)
			(layers "F.Cu" "F.Mask")
			(net 1 "GND")
			(pinfunction "B33")
			(pintype "passive")
		)
		(pad "B34" smd rect
			(at 5 -0.2)
			(size 0.38 1.72)
			(layers "F.Cu" "F.Mask")
			(net 90 "SGPIO1_DO")
			(pinfunction "B34")
			(pintype "passive")
		)
		(pad "B35" smd rect
			(at 5.6 -0.2)
			(size 0.38 1.72)
			(layers "F.Cu" "F.Mask")
			(net 694 "Net-(J9-PadB35)")
			(pinfunction "B35")
			(pintype "passive")
		)
		(pad "B36" smd rect
			(at 6.2 -0.2)
			(size 0.38 1.72)
			(layers "F.Cu" "F.Mask")
			(net 92 "SGPIO1_DI")
			(pinfunction "B36")
			(pintype "passive")
		)
		(pad "B37" smd rect
			(at 6.8 -0.2)
			(size 0.38 1.72)
			(layers "F.Cu" "F.Mask")
			(net 93 "SGPIO1_LD")
			(pinfunction "B37")
			(pintype "passive")
		)
		(pad "B38" smd rect
			(at 7.4 0)
			(size 0.38 2.12)
			(layers "F.Cu" "F.Mask")
			(net 1 "GND")
			(pinfunction "B38")
			(pintype "passive")
		)
		(pad "B39" smd rect
			(at 8 -0.2)
			(size 0.38 1.72)
			(layers "F.Cu" "F.Mask")
			(net 94 "SGPIO_RESET_N")
			(pinfunction "B39")
			(pintype "passive")
		)
		(pad "B40" smd rect
			(at 8.6 -0.2)
			(size 0.38 1.72)
			(layers "F.Cu" "F.Mask")
			(net 95 "SGPIO_INTR_N")
			(pinfunction "B40")
			(pintype "passive")
		)
		(pad "B41" smd rect
			(at 9.2 -0.2)
			(size 0.38 1.72)
			(layers "F.Cu" "F.Mask")
			(net 287 "3V0_BAT")
			(pinfunction "B41")
			(pintype "passive")
		)
		(pad "B42" smd rect
			(at 9.8 -0.2)
			(size 0.38 1.72)
			(layers "F.Cu" "F.Mask")
			(net 96 "QSPI0_CS1_N")
			(pinfunction "B42")
			(pintype "passive")
		)
		(pad "B43" smd rect
			(at 14.715 -0.2)
			(size 0.38 1.72)
			(layers "F.Cu" "F.Mask")
			(net 97 "QSPI1_CLK")
			(pinfunction "B43")
			(pintype "passive")
		)
		(pad "B44" smd rect
			(at 15.3 -0.2)
			(size 0.38 1.72)
			(layers "F.Cu" "F.Mask")
			(net 98 "QSPI1_CS0_N")
			(pinfunction "B44")
			(pintype "passive")
		)
		(pad "B45" smd rect
			(at 15.9 -0.2)
			(size 0.38 1.72)
			(layers "F.Cu" "F.Mask")
			(net 99 "QSPI1_D0")
			(pinfunction "B45")
			(pintype "passive")
		)
		(pad "B46" smd rect
			(at 16.5 -0.2)
			(size 0.38 1.72)
			(layers "F.Cu" "F.Mask")
			(net 100 "QSPI1_D1")
			(pinfunction "B46")
			(pintype "passive")
		)
		(pad "B47" smd rect
			(at 17.1 -0.2)
			(size 0.38 1.72)
			(layers "F.Cu" "F.Mask")
			(net 101 "QSPI1_D2")
			(pinfunction "B47")
			(pintype "passive")
		)
		(pad "B48" smd rect
			(at 17.7 -0.2)
			(size 0.38 1.72)
			(layers "F.Cu" "F.Mask")
			(net 102 "QSPI1_D3")
			(pinfunction "B48")
			(pintype "passive")
		)
		(pad "B49" smd rect
			(at 18.3 0)
			(size 0.38 2.12)
			(layers "F.Cu" "F.Mask")
			(net 1 "GND")
			(pinfunction "B49")
			(pintype "passive")
		)
		(pad "B50" smd rect
			(at 18.9 -0.2)
			(size 0.38 1.72)
			(layers "F.Cu" "F.Mask")
			(net 383 "USB2_D_P")
			(pinfunction "B50")
			(pintype "passive")
		)
		(pad "B51" smd rect
			(at 19.5 -0.2)
			(size 0.38 1.72)
			(layers "F.Cu" "F.Mask")
			(net 384 "USB2_D_N")
			(pinfunction "B51")
			(pintype "passive")
		)
		(pad "B52" smd rect
			(at 20.1 0)
			(size 0.38 2.12)
			(layers "F.Cu" "F.Mask")
			(net 1 "GND")
			(pinfunction "B52")
			(pintype "passive")
		)
		(pad "B53" smd rect
			(at 20.7 -0.2)
			(size 0.38 1.72)
			(layers "F.Cu" "F.Mask")
			(net 385 "USB1_D_P")
			(pinfunction "B53")
			(pintype "passive")
		)
		(pad "B54" smd rect
			(at 21.3 -0.2)
			(size 0.38 1.72)
			(layers "F.Cu" "F.Mask")
			(net 386 "USB1_D_N")
			(pinfunction "B54")
			(pintype "passive")
		)
		(pad "B55" smd rect
			(at 21.9 0)
			(size 0.38 2.12)
			(layers "F.Cu" "F.Mask")
			(net 1 "GND")
			(pinfunction "B55")
			(pintype "passive")
		)
		(pad "B56" smd rect
			(at 22.5 -0.2)
			(size 0.38 1.72)
			(layers "F.Cu" "F.Mask")
			(net 359 "PCIE_HPM_CLK_P")
			(pinfunction "B56")
			(pintype "passive")
		)
		(pad "B57" smd rect
			(at 23.1 -0.2)
			(size 0.38 1.72)
			(layers "F.Cu" "F.Mask")
			(net 360 "PCIE_HPM_CLK_N")
			(pinfunction "B57")
			(pintype "passive")
		)
		(pad "B58" smd rect
			(at 23.7 0)
			(size 0.38 2.12)
			(layers "F.Cu" "F.Mask")
			(net 1 "GND")
			(pinfunction "B58")
			(pintype "passive")
		)
		(pad "B59" smd rect
			(at 24.3 -0.2)
			(size 0.38 1.72)
			(layers "F.Cu" "F.Mask")
			(net 351 "PCIE_HPM_TX[0]_P")
			(pinfunction "B59")
			(pintype "passive")
		)
		(pad "B60" smd rect
			(at 24.9 -0.2)
			(size 0.38 1.72)
			(layers "F.Cu" "F.Mask")
			(net 353 "PCIE_HPM_TX[0]_N")
			(pinfunction "B60")
			(pintype "passive")
		)
		(pad "B61" smd rect
			(at 25.5 0)
			(size 0.38 2.12)
			(layers "F.Cu" "F.Mask")
			(net 1 "GND")
			(pinfunction "B61")
			(pintype "passive")
		)
		(pad "B62" smd rect
			(at 26.1 -0.2)
			(size 0.38 1.72)
			(layers "F.Cu" "F.Mask")
			(net 352 "PCIE_HPM_TX[1]_P")
			(pinfunction "B62")
			(pintype "passive")
		)
		(pad "B63" smd rect
			(at 26.7 -0.2)
			(size 0.38 1.72)
			(layers "F.Cu" "F.Mask")
			(net 354 "PCIE_HPM_TX[1]_N")
			(pinfunction "B63")
			(pintype "passive")
		)
		(pad "B64" smd rect
			(at 27.3 0)
			(size 0.38 2.12)
			(layers "F.Cu" "F.Mask")
			(net 1 "GND")
			(pinfunction "B64")
			(pintype "passive")
		)
		(pad "B65" smd rect
			(at 27.9 -0.2)
			(size 0.38 1.72)
			(layers "F.Cu" "F.Mask")
			(net 355 "PCIE_HPM_TX[2]_P")
			(pinfunction "B65")
			(pintype "passive")
		)
		(pad "B66" smd rect
			(at 28.5 -0.2)
			(size 0.38 1.72)
			(layers "F.Cu" "F.Mask")
			(net 357 "PCIE_HPM_TX[2]_N")
			(pinfunction "B66")
			(pintype "passive")
		)
		(pad "B67" smd rect
			(at 29.1 0)
			(size 0.38 2.12)
			(layers "F.Cu" "F.Mask")
			(net 1 "GND")
			(pinfunction "B67")
			(pintype "passive")
		)
		(pad "B68" smd rect
			(at 29.7 -0.2)
			(size 0.38 1.72)
			(layers "F.Cu" "F.Mask")
			(net 356 "PCIE_HPM_TX[3]_P")
			(pinfunction "B68")
			(pintype "passive")
		)
		(pad "B69" smd rect
			(at 30.3 -0.2)
			(size 0.38 1.72)
			(layers "F.Cu" "F.Mask")
			(net 358 "PCIE_HPM_TX[3]_N")
			(pinfunction "B69")
			(pintype "passive")
		)
		(pad "B70" smd rect
			(at 30.9 0)
			(size 0.38 2.12)
			(layers "F.Cu" "F.Mask")
			(net 1 "GND")
			(pinfunction "B70")
			(pintype "passive")
		)
		(pad "OA1" smd rect
			(at -30.4 -0.2)
			(size 0.38 1.72)
			(layers "B.Cu" "B.Mask")
			(net 59 "P12V_AUX")
			(pinfunction "OA1")
			(pintype "passive")
		)
		(pad "OA2" smd rect
			(at -29.8 -0.2)
			(size 0.38 1.72)
			(layers "B.Cu" "B.Mask")
			(net 59 "P12V_AUX")
			(pinfunction "OA2")
			(pintype "passive")
		)
		(pad "OA3" smd rect
			(at -29.2 0)
			(size 0.38 2.12)
			(layers "B.Cu" "B.Mask")
			(net 1 "GND")
			(pinfunction "OA3")
			(pintype "passive")
		)
		(pad "OA4" smd rect
			(at -28.6 0)
			(size 0.38 2.12)
			(layers "B.Cu" "B.Mask")
			(net 1 "GND")
			(pinfunction "OA4")
			(pintype "passive")
		)
		(pad "OA5" smd rect
			(at -28 -0.2)
			(size 0.38 1.72)
			(layers "B.Cu" "B.Mask")
			(net 49 "I3C[0]_SCL")
			(pinfunction "OA5")
			(pintype "passive")
		)
		(pad "OA6" smd rect
			(at -27.4 -0.2)
			(size 0.38 1.72)
			(layers "B.Cu" "B.Mask")
			(net 48 "I3C[0]_SDA")
			(pinfunction "OA6")
			(pintype "passive")
		)
		(pad "OA7" smd rect
			(at -26.8 -0.2)
			(size 0.38 1.72)
			(layers "B.Cu" "B.Mask")
			(net 52 "I3C[1]_SCL")
			(pinfunction "OA7")
			(pintype "passive")
		)
		(pad "OA8" smd rect
			(at -26.2 -0.2)
			(size 0.38 1.72)
			(layers "B.Cu" "B.Mask")
			(net 51 "I3C[1]_SDA")
			(pinfunction "OA8")
			(pintype "passive")
		)
		(pad "OA9" smd rect
			(at -25.6 -0.2)
			(size 0.38 1.72)
			(layers "B.Cu" "B.Mask")
			(net 47 "I3C[2]_SCL")
			(pinfunction "OA9")
			(pintype "passive")
		)
		(pad "OA10" smd rect
			(at -25 -0.2)
			(size 0.38 1.72)
			(layers "B.Cu" "B.Mask")
			(net 50 "I3C[2]_SDA")
			(pinfunction "OA10")
			(pintype "passive")
		)
		(pad "OA11" smd rect
			(at -24.4 -0.2)
			(size 0.38 1.72)
			(layers "B.Cu" "B.Mask")
			(net 54 "I3C[3]_SCL")
			(pinfunction "OA11")
			(pintype "passive")
		)
		(pad "OA12" smd rect
			(at -23.8 -0.2)
			(size 0.38 1.72)
			(layers "B.Cu" "B.Mask")
			(net 53 "I3C[3]_SDA")
			(pinfunction "OA12")
			(pintype "passive")
		)
		(pad "OA13" smd rect
			(at -23.2 0)
			(size 0.38 2.12)
			(layers "B.Cu" "B.Mask")
			(net 1 "GND")
			(pinfunction "OA13")
			(pintype "passive")
		)
		(pad "OA14" smd rect
			(at -22.6 -0.2)
			(size 0.38 1.72)
			(layers "B.Cu" "B.Mask")
			(net 244 "/Edge connector/VIRTUAL_RESEAT")
			(pinfunction "OA14")
			(pintype "passive")
		)
		(pad "OB1" smd rect
			(at -30.4 -0.2)
			(size 0.38 1.72)
			(layers "F.Cu" "F.Mask")
			(net 59 "P12V_AUX")
			(pinfunction "OB1")
			(pintype "passive")
		)
		(pad "OB2" smd rect
			(at -29.8 -0.2)
			(size 0.38 1.72)
			(layers "F.Cu" "F.Mask")
			(net 59 "P12V_AUX")
			(pinfunction "OB2")
			(pintype "passive")
		)
		(pad "OB3" smd rect
			(at -29.2 -0.2)
			(size 0.38 1.72)
			(layers "F.Cu" "F.Mask")
			(net 243 "/Edge connector/PRSNT0_N")
			(pinfunction "OB3")
			(pintype "passive")
		)
		(pad "OB4" smd rect
			(at -28.6 0)
			(size 0.38 2.12)
			(layers "F.Cu" "F.Mask")
			(net 1 "GND")
			(pinfunction "OB4")
			(pintype "passive")
		)
		(pad "OB5" smd rect
			(at -28 -0.2)
			(size 0.38 1.72)
			(layers "F.Cu" "F.Mask")
			(net 40 "UART1_SCM_TX")
			(pinfunction "OB5")
			(pintype "passive")
		)
		(pad "OB6" smd rect
			(at -27.4 -0.2)
			(size 0.38 1.72)
			(layers "F.Cu" "F.Mask")
			(net 33 "UART1_SCM_RX")
			(pinfunction "OB6")
			(pintype "passive")
		)
		(pad "OB7" smd rect
			(at -26.8 0)
			(size 0.38 2.12)
			(layers "F.Cu" "F.Mask")
			(net 1 "GND")
			(pinfunction "OB7")
			(pintype "passive")
		)
		(pad "OB8" smd rect
			(at -26.2 -0.2)
			(size 0.38 1.72)
			(layers "F.Cu" "F.Mask")
			(net 35 "UART0_SCM_TX")
			(pinfunction "OB8")
			(pintype "passive")
		)
		(pad "OB9" smd rect
			(at -25.6 -0.2)
			(size 0.38 1.72)
			(layers "F.Cu" "F.Mask")
			(net 39 "UART0_SCM_RX")
			(pinfunction "OB9")
			(pintype "passive")
		)
		(pad "OB10" smd rect
			(at -25 0)
			(size 0.38 2.12)
			(layers "F.Cu" "F.Mask")
			(net 1 "GND")
			(pinfunction "OB10")
			(pintype "passive")
		)
		(pad "OB11" smd rect
			(at -24.4 -0.2)
			(size 0.38 1.72)
			(layers "F.Cu" "F.Mask")
			(net 56 "SPI0_CLK")
			(pinfunction "OB11")
			(pintype "passive")
		)
		(pad "OB12" smd rect
			(at -23.8 -0.2)
			(size 0.38 1.72)
			(layers "F.Cu" "F.Mask")
			(net 55 "SPI0_CS_N")
			(pinfunction "OB12")
			(pintype "passive")
		)
		(pad "OB13" smd rect
			(at -23.2 -0.2)
			(size 0.38 1.72)
			(layers "F.Cu" "F.Mask")
			(net 57 "SPI0_MOSI")
			(pinfunction "OB13")
			(pintype "passive")
		)
		(pad "OB14" smd rect
			(at -22.6 -0.2)
			(size 0.38 1.72)
			(layers "F.Cu" "F.Mask")
			(net 58 "SPI0_MISO")
			(pinfunction "OB14")
			(pintype "passive")
		)
	)
)
